(kicad_pcb
	(version 20260206)
	(generator "pcbnew")
	(generator_version "10.0")
	(general
		(thickness 1.6)
		(legacy_teardrops no)
	)
	(paper "A4")
	(title_block
		(title "timecard-production-celestica-r4006 — R4006-B0001-02_R01.brd")
		(comment 1 "Time Appliance Project (Time Card) / footprints 311-316 of 1113")
	)
	(layers
		(0 "F.Cu" signal "TOP")
		(4 "In1.Cu" signal "L02_GND1")
		(6 "In2.Cu" signal "L03_SIG1")
		(8 "In3.Cu" signal "L04_GND2")
		(10 "In4.Cu" signal "L05_VCC1")
		(12 "In5.Cu" signal "L06_VCC2")
		(14 "In6.Cu" signal "L07_GND3")
		(16 "In7.Cu" signal "L08_SIG2")
		(18 "In8.Cu" signal "L09_GND4")
		(2 "B.Cu" signal "BOTTOM")
		(9 "F.Adhes" user "F.Adhesive")
		(11 "B.Adhes" user "B.Adhesive")
		(13 "F.Paste" user "Package Geometry/Pastemask Top")
		(15 "B.Paste" user "Package Geometry/Pastemask Bottom")
		(5 "F.SilkS" user "Ref Des/Silkscreen Top")
		(7 "B.SilkS" user "Ref Des/Silkscreen Bottom")
		(1 "F.Mask" user "Board Geometry/Soldermask Top")
		(3 "B.Mask" user "Board Geometry/Soldermask Bottom")
		(17 "Dwgs.User" user "User.Drawings")
		(19 "Cmts.User" user "User.Comments")
		(21 "Eco1.User" user "User.Eco1")
		(23 "Eco2.User" user "User.Eco2")
		(25 "Edge.Cuts" user "Board Geometry/Outline")
		(27 "Margin" user)
		(31 "F.CrtYd" user "Package Geometry/Place Bound Top")
		(29 "B.CrtYd" user "Package Geometry/Place Bound Bottom")
		(35 "F.Fab" user "Ref Des/Assembly Top")
		(33 "B.Fab" user "Ref Des/Assembly Bottom")
	)
	(footprint ""
		(layer "F.Cu")
		(at 158.115 -50.894996 -90)
		(property "Reference" "C61"
			(at -0.794004 2.50063 90)
			(unlocked yes)
			(layer "F.SilkS")
			(effects
				(font
					(size 0.7874 0.5842)
					(thickness 0.1524)
				)
			)
		)
		(property "Value" "VAL*"
			(at 0.0762 3.134106 270)
			(unlocked yes)
			(layer "F.Fab")
			(hide yes)
			(effects
				(font
					(size 0.7874 0.5842)
					(thickness 0.1524)
				)
			)
		)
		(property "Tolerance" "TOL*"
			(at 0.0762 4.048506 270)
			(unlocked yes)
			(layer "Cmts.User")
			(hide yes)
			(effects
				(font
					(size 0.7874 0.5842)
					(thickness 0.1524)
				)
			)
		)
		(property "User Part Number" "PARTNUM*"
			(at 0.1016 5.013706 270)
			(unlocked yes)
			(layer "Cmts.User")
			(hide yes)
			(effects
				(font
					(size 0.7874 0.5842)
					(thickness 0.1524)
				)
			)
		)
		(property "Device Type" "CAPACITOR-G107-0F106-EM,10UF,2A"
			(at 0.0508 2.194306 270)
			(unlocked yes)
			(layer "F.Fab")
			(hide yes)
			(effects
				(font
					(size 0.7874 0.5842)
					(thickness 0.1524)
				)
			)
		)
		(duplicate_pad_numbers_are_jumpers no)
		(fp_line
			(start -1.5748 0.9398)
			(end 1.5748 0.9398)
			(stroke
				(width 0.1)
				(type default)
			)
			(layer "F.SilkS")
		)
		(fp_line
			(start 1.5748 0.9398)
			(end 1.5748 -0.9398)
			(stroke
				(width 0.1)
				(type default)
			)
			(layer "F.SilkS")
		)
		(fp_line
			(start -1.5748 -0.9398)
			(end -1.5748 0.9398)
			(stroke
				(width 0.1)
				(type default)
			)
			(layer "F.SilkS")
		)
		(fp_line
			(start 1.5748 -0.9398)
			(end -1.5748 -0.9398)
			(stroke
				(width 0.1)
				(type default)
			)
			(layer "F.SilkS")
		)
		(fp_rect
			(start 1.5748 -0.9398)
			(end -1.5748 0.9398)
			(stroke
				(width 0)
				(type default)
			)
			(fill no)
			(layer "F.CrtYd")
		)
		(fp_line
			(start -1.016 0.635)
			(end 1.016 0.635)
			(stroke
				(width 0.1)
				(type default)
			)
			(layer "F.Fab")
		)
		(fp_line
			(start 1.016 0.635)
			(end 1.016 -0.635)
			(stroke
				(width 0.1)
				(type default)
			)
			(layer "F.Fab")
		)
		(fp_line
			(start -1.016 -0.635)
			(end -1.016 0.635)
			(stroke
				(width 0.1)
				(type default)
			)
			(layer "F.Fab")
		)
		(fp_line
			(start 1.016 -0.635)
			(end -1.016 -0.635)
			(stroke
				(width 0.1)
				(type default)
			)
			(layer "F.Fab")
		)
		(pad "1" smd rect
			(at -0.8382 0 270)
			(size 0.9652 1.3716)
			(layers "F.Cu" "F.Mask" "F.Paste")
			(net "XP5R0V_USB_CONN")
		)
		(pad "2" smd rect
			(at 0.8382 0 270)
			(size 0.9652 1.3716)
			(layers "F.Cu" "F.Mask" "F.Paste")
			(net "SG")
		)
		(zone
			(layer "F.Cu")
			(hatch none 0.5)
			(connect_pads
				(clearance 0)
			)
			(min_thickness 0.25)
			(keepout
				(tracks allowed)
				(vias not_allowed)
				(pads allowed)
				(copperpour not_allowed)
				(footprints allowed)
			)
			(placement
				(enabled no)
				(sheetname "")
			)
			(fill
				(thermal_gap 0.5)
				(thermal_bridge_width 0.5)
				(island_removal_mode 0)
			)
			(polygon
				(pts
					(xy 158.75 -50.666396) (xy 158.75 -51.123596) (xy 157.48 -51.123596) (xy 157.48 -50.666396)
				)
			)
		)
	)
	(footprint ""
		(layer "F.Cu")
		(at 105.41 -31.369 90)
		(property "Reference" "TP195"
			(at 0 0 90)
			(layer "F.SilkS")
			(hide yes)
			(effects
				(font
					(size 1.27 1.27)
				)
			)
		)
		(property "Value" ""
			(at 0 0 90)
			(layer "F.Fab")
			(effects
				(font
					(size 1.27 1.27)
				)
			)
		)
		(property "Device Type" "TP_PIONT-TP010CT020B030_PTH-TPA"
			(at -1.341882 0.996696 90)
			(unlocked yes)
			(layer "F.Fab")
			(hide yes)
			(effects
				(font
					(size 0.7874 0.5842)
					(thickness 0.1524)
				)
				(justify left)
			)
		)
		(duplicate_pad_numbers_are_jumpers no)
		(fp_poly
			(pts
				(arc
					(start 0 0.889)
					(mid 0 -0.889)
					(end 0 0.889)
				)
			)
			(stroke
				(width 0)
				(type default)
			)
			(fill no)
			(layer "B.CrtYd")
		)
		(fp_poly
			(pts
				(arc
					(start 0 0.889)
					(mid 0 -0.889)
					(end 0 0.889)
				)
			)
			(stroke
				(width 0)
				(type default)
			)
			(fill no)
			(layer "F.CrtYd")
		)
		(pad "1" thru_hole circle
			(at 0 0 90)
			(size 0.508 0.508)
			(drill 0.254)
			(layers "*.Cu" "*.Mask")
			(remove_unused_layers no)
			(net "IO_L23P_35")
			(clearance 0.1016)
			(padstack
				(mode front_inner_back)
				(layer "Inner"
					(shape circle)
					(size 0.508 0.508)
					(clearance 0.1016)
				)
				(layer "B.Cu"
					(shape circle)
					(size 0.762 0.762)
					(clearance -0.0254)
				)
			)
		)
	)
	(footprint ""
		(layer "F.Cu")
		(at 96.8756 -78.5368)
		(property "Reference" "R140"
			(at 0.0254 -1.17983 0)
			(unlocked yes)
			(layer "F.SilkS")
			(effects
				(font
					(size 0.7874 0.5842)
					(thickness 0.1524)
				)
			)
		)
		(property "Value" "VAL*"
			(at 0.02032 2.13233 0)
			(unlocked yes)
			(layer "F.Fab")
			(hide yes)
			(effects
				(font
					(size 0.7874 0.5842)
					(thickness 0.1524)
				)
			)
		)
		(property "Device Type" "RESISTOR-G155-100R0-J0,0OHM,-"
			(at 0.008382 1.210564 0)
			(unlocked yes)
			(layer "F.Fab")
			(hide yes)
			(effects
				(font
					(size 0.7874 0.5842)
					(thickness 0.1524)
				)
			)
		)
		(property "User Part Number" "PARTNUM*"
			(at 0.02032 4.024884 0)
			(unlocked yes)
			(layer "Cmts.User")
			(hide yes)
			(effects
				(font
					(size 0.7874 0.5842)
					(thickness 0.1524)
				)
			)
		)
		(property "Tolerance" "TOL*"
			(at 0.044704 3.05435 0)
			(unlocked yes)
			(layer "Cmts.User")
			(hide yes)
			(effects
				(font
					(size 0.7874 0.5842)
					(thickness 0.1524)
				)
			)
		)
		(duplicate_pad_numbers_are_jumpers no)
		(fp_line
			(start -1.143 -0.5588)
			(end -1.143 0.5588)
			(stroke
				(width 0.1)
				(type default)
			)
			(layer "F.SilkS")
		)
		(fp_line
			(start -1.143 0.5588)
			(end 1.143 0.5588)
			(stroke
				(width 0.1)
				(type default)
			)
			(layer "F.SilkS")
		)
		(fp_line
			(start 1.143 -0.5588)
			(end -1.143 -0.5588)
			(stroke
				(width 0.1)
				(type default)
			)
			(layer "F.SilkS")
		)
		(fp_line
			(start 1.143 0.5588)
			(end 1.143 -0.5588)
			(stroke
				(width 0.1)
				(type default)
			)
			(layer "F.SilkS")
		)
		(fp_rect
			(start -1.143 -0.5588)
			(end 1.143 0.5588)
			(stroke
				(width 0)
				(type default)
			)
			(fill no)
			(layer "F.CrtYd")
		)
		(fp_line
			(start -0.508 -0.3048)
			(end -0.508 0.3048)
			(stroke
				(width 0.1)
				(type default)
			)
			(layer "F.Fab")
		)
		(fp_line
			(start -0.508 0.3048)
			(end 0.508 0.3048)
			(stroke
				(width 0.1)
				(type default)
			)
			(layer "F.Fab")
		)
		(fp_line
			(start 0.508 -0.3048)
			(end -0.508 -0.3048)
			(stroke
				(width 0.1)
				(type default)
			)
			(layer "F.Fab")
		)
		(fp_line
			(start 0.508 0.3048)
			(end 0.508 -0.3048)
			(stroke
				(width 0.1)
				(type default)
			)
			(layer "F.Fab")
		)
		(pad "1" smd rect
			(at -0.5334 0)
			(size 0.7112 0.6096)
			(layers "F.Cu" "F.Mask" "F.Paste")
			(net "XP1R0V_FPGA_PG")
		)
		(pad "2" smd rect
			(at 0.5334 0)
			(size 0.7112 0.6096)
			(layers "F.Cu" "F.Mask" "F.Paste")
			(net "XP1R2V_EN_R")
		)
		(zone
			(layer "F.Cu")
			(hatch none 0.5)
			(connect_pads
				(clearance 0)
			)
			(min_thickness 0.25)
			(keepout
				(tracks allowed)
				(vias not_allowed)
				(pads allowed)
				(copperpour not_allowed)
				(footprints allowed)
			)
			(placement
				(enabled no)
				(sheetname "")
			)
			(fill
				(thermal_gap 0.5)
				(thermal_bridge_width 0.5)
				(island_removal_mode 0)
			)
			(polygon
				(pts
					(xy 96.7994 -78.8416) (xy 96.7994 -78.232) (xy 96.9518 -78.232) (xy 96.9518 -78.8416)
				)
			)
		)
	)
	(footprint ""
		(layer "F.Cu")
		(at 98.044 -95.4532 180)
		(property "Reference" "R449"
			(at 1.143 3.05943 0)
			(unlocked yes)
			(layer "F.SilkS")
			(effects
				(font
					(size 0.7874 0.5842)
					(thickness 0.1524)
				)
			)
		)
		(property "Value" "VAL*"
			(at 0.02032 2.13233 180)
			(unlocked yes)
			(layer "F.Fab")
			(hide yes)
			(effects
				(font
					(size 0.7874 0.5842)
					(thickness 0.1524)
				)
			)
		)
		(property "Tolerance" "TOL*"
			(at 0.044704 3.05435 180)
			(unlocked yes)
			(layer "Cmts.User")
			(hide yes)
			(effects
				(font
					(size 0.7874 0.5842)
					(thickness 0.1524)
				)
			)
		)
		(property "User Part Number" "PARTNUM*"
			(at 0.02032 4.024884 180)
			(unlocked yes)
			(layer "Cmts.User")
			(hide yes)
			(effects
				(font
					(size 0.7874 0.5842)
					(thickness 0.1524)
				)
			)
		)
		(property "Device Type" "RESISTOR-G155-133R0-01,33OHM,1%"
			(at 0.008382 1.210564 180)
			(unlocked yes)
			(layer "F.Fab")
			(hide yes)
			(effects
				(font
					(size 0.7874 0.5842)
					(thickness 0.1524)
				)
			)
		)
		(duplicate_pad_numbers_are_jumpers no)
		(fp_line
			(start 1.143 0.5588)
			(end 1.143 -0.5588)
			(stroke
				(width 0.1)
				(type default)
			)
			(layer "F.SilkS")
		)
		(fp_line
			(start 1.143 -0.5588)
			(end -1.143 -0.5588)
			(stroke
				(width 0.1)
				(type default)
			)
			(layer "F.SilkS")
		)
		(fp_line
			(start -1.143 0.5588)
			(end 1.143 0.5588)
			(stroke
				(width 0.1)
				(type default)
			)
			(layer "F.SilkS")
		)
		(fp_line
			(start -1.143 -0.5588)
			(end -1.143 0.5588)
			(stroke
				(width 0.1)
				(type default)
			)
			(layer "F.SilkS")
		)
		(fp_poly
			(pts
				(xy -1.143 0.5588) (xy 1.143 0.5588) (xy 1.143 -0.5588) (xy -1.143 -0.5588)
			)
			(stroke
				(width 0)
				(type default)
			)
			(fill no)
			(layer "F.CrtYd")
		)
		(fp_line
			(start 0.508 0.3048)
			(end 0.508 -0.3048)
			(stroke
				(width 0.1)
				(type default)
			)
			(layer "F.Fab")
		)
		(fp_line
			(start 0.508 -0.3048)
			(end -0.508 -0.3048)
			(stroke
				(width 0.1)
				(type default)
			)
			(layer "F.Fab")
		)
		(fp_line
			(start -0.508 0.3048)
			(end 0.508 0.3048)
			(stroke
				(width 0.1)
				(type default)
			)
			(layer "F.Fab")
		)
		(fp_line
			(start -0.508 -0.3048)
			(end -0.508 0.3048)
			(stroke
				(width 0.1)
				(type default)
			)
			(layer "F.Fab")
		)
		(pad "1" smd rect
			(at -0.5334 0 180)
			(size 0.7112 0.6096)
			(layers "F.Cu" "F.Mask" "F.Paste")
			(net "MUX1_SEL")
		)
		(pad "2" smd rect
			(at 0.5334 0 180)
			(size 0.7112 0.6096)
			(layers "F.Cu" "F.Mask" "F.Paste")
			(net "FT4232_MUX1_SEL")
		)
		(zone
			(layer "F.Cu")
			(hatch none 0.5)
			(connect_pads
				(clearance 0)
			)
			(min_thickness 0.25)
			(keepout
				(tracks allowed)
				(vias not_allowed)
				(pads allowed)
				(copperpour not_allowed)
				(footprints allowed)
			)
			(placement
				(enabled no)
				(sheetname "")
			)
			(fill
				(thermal_gap 0.5)
				(thermal_bridge_width 0.5)
				(island_removal_mode 0)
			)
			(polygon
				(pts
					(xy 98.1202 -95.758) (xy 97.9678 -95.758) (xy 97.9678 -95.1484) (xy 98.1202 -95.1484)
				)
			)
		)
		(zone
			(layer "F.Cu")
			(hatch none 0.5)
			(connect_pads
				(clearance 0)
			)
			(min_thickness 0.25)
			(keepout
				(tracks not_allowed)
				(vias allowed)
				(pads allowed)
				(copperpour not_allowed)
				(footprints allowed)
			)
			(placement
				(enabled no)
				(sheetname "")
			)
			(fill
				(thermal_gap 0.5)
				(thermal_bridge_width 0.5)
				(island_removal_mode 0)
			)
			(polygon
				(pts
					(xy 98.1202 -95.758) (xy 97.9678 -95.758) (xy 97.9678 -95.1484) (xy 98.1202 -95.1484)
				)
			)
		)
	)
	(footprint ""
		(layer "F.Cu")
		(at 82.169 -66.802)
		(property "Reference" "TP16"
			(at -2.3114 -0.73025 0)
			(unlocked yes)
			(layer "F.SilkS")
			(effects
				(font
					(size 0.635 0.4064)
					(thickness 0.1524)
				)
				(justify left)
			)
		)
		(property "Value" ""
			(at 0 0 0)
			(layer "F.Fab")
			(effects
				(font
					(size 1.27 1.27)
				)
			)
		)
		(property "Device Type" "TP_PIONT-TP010CT020B030_PTH-TPA"
			(at -1.341882 0.996696 0)
			(unlocked yes)
			(layer "F.Fab")
			(hide yes)
			(effects
				(font
					(size 0.7874 0.5842)
					(thickness 0.000001)
				)
				(justify left)
			)
		)
		(duplicate_pad_numbers_are_jumpers no)
		(fp_poly
			(pts
				(arc
					(start 0.889 0)
					(mid -0.889 0)
					(end 0.889 0)
				)
			)
			(stroke
				(width 0)
				(type default)
			)
			(fill no)
			(layer "B.CrtYd")
		)
		(fp_poly
			(pts
				(arc
					(start 0.889 0)
					(mid -0.889 0)
					(end 0.889 0)
				)
			)
			(stroke
				(width 0)
				(type default)
			)
			(fill no)
			(layer "F.CrtYd")
		)
		(pad "1" thru_hole circle
			(at 0 0)
			(size 0.508 0.508)
			(drill 0.254)
			(layers "*.Cu" "*.Mask")
			(remove_unused_layers no)
			(net "R_BNO080_RST_N")
			(clearance 0.1016)
			(padstack
				(mode front_inner_back)
				(layer "Inner"
					(shape circle)
					(size 0.508 0.508)
					(clearance 0.1016)
				)
				(layer "B.Cu"
					(shape circle)
					(size 0.762 0.762)
					(clearance -0.0254)
				)
			)
		)
	)
	(footprint ""
		(layer "F.Cu")
		(at 73.787 -124.46)
		(property "Reference" "SP39"
			(at 0 0 0)
			(layer "F.SilkS")
			(hide yes)
			(effects
				(font
					(size 1.27 1.27)
				)
			)
		)
		(property "Value" ""
			(at 0 0 0)
			(layer "F.Fab")
			(effects
				(font
					(size 1.27 1.27)
				)
			)
		)
		(duplicate_pad_numbers_are_jumpers no)
	)
)
